# Bryce Canyon_IOM_IOC_Stackup.xlsx — PCB Test Plan_HVM(0-90) (pcb-stackup)
|  | Board vendor give feedback of quantity in yellow columns based on the AQL table or description. |  |  |  |  |  |  |  |  |  |  |  |  |  |  |
|  | Wiwynn PM give feedback in blue columns |  |  |  |  |  |  |  |  |  |  |  |  |  |  |
| Person to be informed : PCB vendor, EE, SI, PM, PSM, Buyer, SQM |  |  |  |  |  |  |  |  |  |  |  |  |  |  |  |
| Simple flow : SI (test requirements) -> PM/AM (Total PCBS demand) -> Buyer -> Board Vendor (yellow column feedback) -> Buyer -> Person to be informed (Check and Track) |  |  |  |  |  |  |  |  |  |  |  |  |  |  |  |
| PO(purchase order) : If there are many POs for this PCB, 1st sample quantity is based on 1st PO, 2nd sample quantity is based on 2nd PO. |  |  |  |  |  |  |  |  |  |  |  |  |  |  |  |
| Project Name | PCB name | PCB# (1XXXX-XX) | Product Stage | Batch# | PCB Vendor | PCBs Demand | Delta-L Coupon (PCB Vendor) | Delta-L Coupon (3rd Party Lab) | Impedance Coupon (PCB Vendor) | In-board trace correlation (PCB Vendor) | X-section Analysis (PCB Vendor) | IST (3rd Party Lab) | Resin Void (PCB Vendor) | IPC-6012D (3rd Party Lab) | Note 1 |
| Bryce Canyon | IOM IOC | 16318-2 | HVM(0-90 days) | N/A |  |  | Yes | Yes | Yes | Yes | No | Yes | No | No | Need Test? (Yes, No) |
| Tracking Code On Both Of Coupon And PCB |  |  |  |  |  |  | Follow rules of board vendor | Follow rules of board vendor | Follow rules of board vendor | Follow rules of board vendor |  | Follow rules of board vendor |  |  |  |
| Test Item Acceptance Criteria |  |  |  |  |  |  | Failure Rate ≦0.3% | Failure Rate ≦0.3% | Cpk≧1.0 | Fail : 0 Variation ≦5% |  | Fail: 0 |  |  |  |
| Test Item Sampling Quantity |  |  |  |  |  |  | AQL 1, level 1 | 30 pcs | AQL 1, level 1 | AQL 1, level 1 |  | 5 pcs/production lot, with max total of 30 pcs |  |  |  |
| Test Time (working days) |  |  |  |  |  |  | 5 | 5 | 5 | 5 |  | 20+ |  |  |  |
| Test Item Shipping Quantity |  |  |  |  |  |  |  | 30 pcs |  |  |  | 5 pcs/production lot, with max total of 30 pcs |  |  |  |
| Shipping Address |  |  |  |  |  |  |  | 8F, 90, Sec. 1, Xintai 5th Rd., Xizhi Dist., New Taipei City 22102, Taiwan, R.O.C. |  |  |  | 8F, 90, Sec. 1, Xintai 5th Rd., Xizhi Dist., New Taipei City 22102, Taiwan, R.O.C. |  |  |  |
| Receiver Name |  |  |  |  |  |  |  | Karol Lai |  |  |  | Karol Lai |  |  |  |
| Receiver Phone# |  |  |  |  |  |  |  | 886-2-6612-7507 |  |  |  | 886-2-6612-7507 |  |  |  |
